# SCM (Grand Teton) — schematic netlist excerpt (pin names and nets, part order shuffled) for the footprints in the layout excerpt that follows; sources: Cadence DE-HDL packaged netlist, KiCad conversion of 12092022_DA0F0TMDCD0_F0T_Management_Board_D_brd_V3_OCP.brd

R765  Q_RES  4.7K 1% CHIP  pkg 0402LF  page 30 : A = P3V3_AUX ; B = UART_BMC_5_TXD_BUF_R
C74  Q_CAP  0.1UF 25V 10% X7R  pkg 0402  page 16 : A = P1V2_AUX ; B = GND

(kicad_pcb
	(version 20260206)
	(generator "pcbnew")
	(generator_version "10.0")
	(general
		(thickness 1.6)
		(legacy_teardrops no)
	)
	(paper "A4")
	(title_block
		(title "12092022_DA0F0TMDCD0_F0T_Management_Board_D_brd_V3_OCP.brd")
		(comment 1 "Grand Teton / footprints 1129-1130 of 1440")
	)
	(layers
		(0 "F.Cu" signal "TOP")
		(4 "In1.Cu" signal "GND")
		(6 "In2.Cu" signal "IN1")
		(8 "In3.Cu" signal "GND1")
		(10 "In4.Cu" signal "IN2")
		(12 "In5.Cu" signal "VCC")
		(14 "In6.Cu" signal "VCC1")
		(16 "In7.Cu" signal "IN3")
		(18 "In8.Cu" signal "GND2")
		(20 "In9.Cu" signal "IN4")
		(22 "In10.Cu" signal "GND3")
		(2 "B.Cu" signal "BOTTOM")
		(9 "F.Adhes" user "F.Adhesive")
		(11 "B.Adhes" user "B.Adhesive")
		(13 "F.Paste" user "Package Geometry/Pastemask Top")
		(15 "B.Paste" user "Package Geometry/Pastemask Bottom")
		(5 "F.SilkS" user "Ref Des/Silkscreen Top")
		(7 "B.SilkS" user "Ref Des/Silkscreen Bottom")
		(1 "F.Mask" user "Board Geometry/Soldermask Top")
		(3 "B.Mask" user "Board Geometry/Soldermask Bottom")
		(17 "Dwgs.User" user "User.Drawings")
		(19 "Cmts.User" user "User.Comments")
		(21 "Eco1.User" user "User.Eco1")
		(23 "Eco2.User" user "User.Eco2")
		(25 "Edge.Cuts" user "Board Geometry/Outline")
		(27 "Margin" user)
		(31 "F.CrtYd" user "Package Geometry/Place Bound Top")
		(29 "B.CrtYd" user "Package Geometry/Place Bound Bottom")
		(35 "F.Fab" user "Ref Des/Assembly Top")
		(33 "B.Fab" user "Ref Des/Assembly Bottom")
	)
	(footprint ""
		(layer "B.Cu")
		(at 60.537598 -50.711862 90)
		(property "Reference" "C74"
			(at 0 0 90)
			(layer "B.SilkS")
			(hide yes)
			(effects
				(font
					(size 1.27 1.27)
				)
				(justify mirror)
			)
		)
		(property "Value" ""
			(at 0 0 90)
			(layer "B.Fab")
			(effects
				(font
					(size 1.27 1.27)
				)
				(justify mirror)
			)
		)
		(duplicate_pad_numbers_are_jumpers no)
		(fp_line
			(start 0.7874 -0.4064)
			(end -0.7874 -0.4064)
			(stroke
				(width 0.1524)
				(type default)
			)
			(layer "B.SilkS")
		)
		(fp_line
			(start -0.7874 -0.4064)
			(end -0.7874 0.4064)
			(stroke
				(width 0.1524)
				(type default)
			)
			(layer "B.SilkS")
		)
		(fp_line
			(start 0.7874 0.4064)
			(end 0.7874 -0.4064)
			(stroke
				(width 0.1524)
				(type default)
			)
			(layer "B.SilkS")
		)
		(fp_line
			(start -0.7874 0.4064)
			(end 0.7874 0.4064)
			(stroke
				(width 0.1524)
				(type default)
			)
			(layer "B.SilkS")
		)
		(fp_line
			(start 0.67945 -0.305054)
			(end 0.12065 -0.305054)
			(stroke
				(width 0.1)
				(type default)
			)
			(layer "B.Fab")
		)
		(fp_line
			(start 0.12065 -0.305054)
			(end 0.12065 -0.2794)
			(stroke
				(width 0.1)
				(type default)
			)
			(layer "B.Fab")
		)
		(fp_line
			(start -0.12065 -0.3048)
			(end -0.67945 -0.3048)
			(stroke
				(width 0.1)
				(type default)
			)
			(layer "B.Fab")
		)
		(fp_line
			(start -0.67945 -0.3048)
			(end -0.67945 0.3048)
			(stroke
				(width 0.1)
				(type default)
			)
			(layer "B.Fab")
		)
		(fp_line
			(start 0.12065 -0.2794)
			(end -0.12065 -0.2794)
			(stroke
				(width 0.1)
				(type default)
			)
			(layer "B.Fab")
		)
		(fp_line
			(start -0.12065 -0.2794)
			(end -0.12065 -0.3048)
			(stroke
				(width 0.1)
				(type default)
			)
			(layer "B.Fab")
		)
		(fp_line
			(start 0.12065 0.2794)
			(end 0.12065 0.3048)
			(stroke
				(width 0.1)
				(type default)
			)
			(layer "B.Fab")
		)
		(fp_line
			(start -0.120396 0.2794)
			(end 0.12065 0.2794)
			(stroke
				(width 0.1)
				(type default)
			)
			(layer "B.Fab")
		)
		(fp_line
			(start 0.67945 0.3048)
			(end 0.67945 -0.305054)
			(stroke
				(width 0.1)
				(type default)
			)
			(layer "B.Fab")
		)
		(fp_line
			(start 0.12065 0.3048)
			(end 0.67945 0.3048)
			(stroke
				(width 0.1)
				(type default)
			)
			(layer "B.Fab")
		)
		(fp_line
			(start -0.120396 0.3048)
			(end -0.120396 0.2794)
			(stroke
				(width 0.1)
				(type default)
			)
			(layer "B.Fab")
		)
		(fp_line
			(start -0.67945 0.3048)
			(end -0.120396 0.3048)
			(stroke
				(width 0.1)
				(type default)
			)
			(layer "B.Fab")
		)
		(pad "1" smd circle
			(at 0.40005 0 270)
			(size 0 0)
			(layers "B.Cu" "B.Mask" "B.Paste")
			(net "P1V2_AUX")
		)
		(pad "2" smd circle
			(at -0.40005 0 270)
			(size 0 0)
			(layers "B.Cu" "B.Mask" "B.Paste")
			(net "GND")
		)
	)
	(footprint ""
		(layer "B.Cu")
		(at 4.6482 -29.5148)
		(property "Reference" "R765"
			(at 0 0 0)
			(layer "B.SilkS")
			(hide yes)
			(effects
				(font
					(size 1.27 1.27)
				)
				(justify mirror)
			)
		)
		(property "Value" ""
			(at 0 0 0)
			(layer "B.Fab")
			(effects
				(font
					(size 1.27 1.27)
				)
				(justify mirror)
			)
		)
		(duplicate_pad_numbers_are_jumpers no)
		(fp_line
			(start -0.7874 -0.4064)
			(end -0.7874 0.4064)
			(stroke
				(width 0.1524)
				(type default)
			)
			(layer "B.SilkS")
		)
		(fp_line
			(start -0.7874 0.4064)
			(end 0.7874 0.4064)
			(stroke
				(width 0.1524)
				(type default)
			)
			(layer "B.SilkS")
		)
		(fp_line
			(start 0.7874 -0.4064)
			(end -0.7874 -0.4064)
			(stroke
				(width 0.1524)
				(type default)
			)
			(layer "B.SilkS")
		)
		(fp_line
			(start 0.7874 0.4064)
			(end 0.7874 -0.4064)
			(stroke
				(width 0.1524)
				(type default)
			)
			(layer "B.SilkS")
		)
		(fp_line
			(start -0.67945 -0.3048)
			(end -0.67945 0.3048)
			(stroke
				(width 0.1)
				(type default)
			)
			(layer "B.Fab")
		)
		(fp_line
			(start -0.67945 0.3048)
			(end -0.120396 0.3048)
			(stroke
				(width 0.1)
				(type default)
			)
			(layer "B.Fab")
		)
		(fp_line
			(start -0.12065 -0.3048)
			(end -0.67945 -0.3048)
			(stroke
				(width 0.1)
				(type default)
			)
			(layer "B.Fab")
		)
		(fp_line
			(start -0.12065 -0.2794)
			(end -0.12065 -0.3048)
			(stroke
				(width 0.1)
				(type default)
			)
			(layer "B.Fab")
		)
		(fp_line
			(start -0.120396 0.2794)
			(end 0.12065 0.2794)
			(stroke
				(width 0.1)
				(type default)
			)
			(layer "B.Fab")
		)
		(fp_line
			(start -0.120396 0.3048)
			(end -0.120396 0.2794)
			(stroke
				(width 0.1)
				(type default)
			)
			(layer "B.Fab")
		)
		(fp_line
			(start 0.12065 -0.305054)
			(end 0.12065 -0.2794)
			(stroke
				(width 0.1)
				(type default)
			)
			(layer "B.Fab")
		)
		(fp_line
			(start 0.12065 -0.2794)
			(end -0.12065 -0.2794)
			(stroke
				(width 0.1)
				(type default)
			)
			(layer "B.Fab")
		)
		(fp_line
			(start 0.12065 0.2794)
			(end 0.12065 0.3048)
			(stroke
				(width 0.1)
				(type default)
			)
			(layer "B.Fab")
		)
		(fp_line
			(start 0.12065 0.3048)
			(end 0.67945 0.3048)
			(stroke
				(width 0.1)
				(type default)
			)
			(layer "B.Fab")
		)
		(fp_line
			(start 0.67945 -0.305054)
			(end 0.12065 -0.305054)
			(stroke
				(width 0.1)
				(type default)
			)
			(layer "B.Fab")
		)
		(fp_line
			(start 0.67945 0.3048)
			(end 0.67945 -0.305054)
			(stroke
				(width 0.1)
				(type default)
			)
			(layer "B.Fab")
		)
		(pad "1" smd circle
			(at 0.40005 0 180)
			(size 0 0)
			(layers "B.Cu" "B.Mask" "B.Paste")
			(net "P3V3_AUX")
		)
		(pad "2" smd circle
			(at -0.40005 0 180)
			(size 0 0)
			(layers "B.Cu" "B.Mask" "B.Paste")
			(net "UART_BMC_5_TXD_BUF_R")
		)
	)
)
